# Barreleye-G2_Tri-mode Expander-DVT-X01-SKU-BOM-X07-20171222_Final.xls.xlsx — DEPOP (bom)
| FOXCONN TECHNOLOGY GROUP |  |  |  |  |  |  |  |  |  |  |  |  |
| BILL OF MATERIAL |  |  |  |  |  |  |  |  |  |  |  |  |
| REV OF  BOM | X07 | CUSTOMER | <name> |  | CUSTOMER P/N |  | PRODUCT CODE |  | PWA  REV | X01 | DATE | 43091 |
| Sourcing (Single/Sole/Multi) | Critical Commodity (Y or N) | Component Class (1, 2, other) | Customer PSL (Y or N) | Item Number | Foxconn P/N | Customer P/N | Part Description | Manufacturer  Full Name | Manufacturer  Part Number | Qty | RoHS Status | Location |
|  | Y | 2 | Y(3) | 1 | 620101T02-015-G | - | CAP,100nF,+/-10%,X7R,16V,G,SMD0402 | MURATA ELEC. NORTH AMERICA | GRM155R71C104K | 6 | Y | PECC3,PELC9,PFCC10,PSCC13,C232,C408 |
|  |  |  | Y(3) | 2 | 620100D00-015-G |  | CAP,100nF,+/-10%,X7R,16V,G,SMD0603 | MURATA ELEC. NORTH AMERICA | GRM188R71C104K | 1 | N | C405 |
|  | ND | ND | Y(1) | 3 | 62012A400-015-G | - | CAP,100nF,+/-10%,X7R,25V,G,SMD0402 | MURATA ELEC. NORTH AMERICA | GRM155R71E104KE14D | 1 | N | C407 |
|  | Y | 2 | Y(3) | 4 | 620102S00-015-G | - | CAP,33pF,+/-5%,NPO(C0G),50V,G,SMD0402 | MURATA ELEC. NORTH AMERICA | GRM1555C1H330J | 1 | Y | PECC5 |
|  | ND | ND | Y(4) | 5 | 61011GQ00-017-G |  | RES,16KOhm,+/-1%,1/16W,G,SMD0402 | KOA SPEER ELECTRONICS, INC. | RK73H1ETTP1602F | 3 | N | PECR18,PECR19,PECR20 |
|  | N | ND | Y(4) | 6 | 610107B00-017-G | K9576 | RES,4.7KOhm,+/-5%,1/16W,G,SMD0402 | KOA SPEER ELECTRONICS, INC. | RK73B1ETTP472J | 2 | N | PECR36,R1414 |
|  | ND |  | Y(4) | 7 | 610113M00-017-G |  | RES,100 Ohm,+/-1%,1/8W,G,SMD0805 | KOA SPEER ELECTRONICS, INC. | RK73H2ATTD1000F | 1 | N | PECR51 |
|  | Y | 2 | Y(3) | 8 | 620103K00-015-G | - | CAP,1nF,+/-10%,X7R,50V,G,SMD0402 | MURATA ELEC. NORTH AMERICA | GRM155R71H102K | 2 | N | PFCC1,PELC1 |
|  | ND | ND | Y(4) | 9 | 61010LA00-017-G | - | RES,4.7KOhm,+/-1%,1/16W,G,SMD0402 | KOA SPEER ELECTRONICS, INC. | RK73H1ETTP4701F | 6 | N | PFCR1,PELR1,PSCR16,R253,R254,PSCR3005 |
|  | N | ND | Y(4) | 10 | 610107A00-017-G | - | RES,0 Ohm,+/-5%,1/16W,G,SMD0402 | KOA SPEER ELECTRONICS, INC. | RK73Z1ETTP | 13 | N | PSLR8,PSGR8,PELR8,PSRR13,PSGR13,PSCR17,R176,R231,R232,R235,R243,R1541,PSCR3014 |
|  | N | Other | Y(4) | 11 | 610101100-017-G |  | RES,1 Ohm,+/-1%,1/10W,G,SMD0603 | KOA SPEER ELECTRONICS, INC. | RK73H1JTTD1R00F | 1 | N | PELR18 |
|  | N | ND | Y(4) | 12 | 61010G500-017-G | - | RES,10KOhm,+/-1%,1/16W,G,SMD0402 | KOA SPEER ELECTRONICS, INC. | RK73H1ETTP1002F | 39 | N | PFCR10,R47,R341,R393,R394,R395,R396,R408,R415,R416,R417,R418,R419,R420,R427,R428,R429,R430,R431,R432,R439,R440,R441,R444,R1488,R1491,R1492,R1494,R1495,R1496,R1498,R1499,R1500,R1502,R1503,R1504,R1545,R1546,R1547 |
|  | N | ND | Y(5) | 13 | 61100J300-017-G |  | RES,121 Ohm,+/-0.1%,1/16W,G,SMD0402 | KOA SPEER ELECTRONICS, INC. | RN731ETTP1210B25 | 2 |  | PSCR18,PSCR3015 |
|  | N |  | Y(5) | 14 | 61100U300-017-G |  | RES,210 Ohm,+/-0.1%,1/16W,G,SMD0402 | KOA SPEER ELECTRONICS, INC. | RN731ETTP2100B25 | 1 |  | PSCR19 |
|  | ND | ND | Y(5) | 15 | 61100BP00-017-G |  | RES,3.09KOhm,+/-0.1%,1/16W,G,SMD0402 | KOA SPEER ELECTRONICS, INC. | RN731ETTP3091B25 | 1 | Y | PSCR3006 |
|  | ND | ND | Y(3) | 16 | 62010QB00-015-G | - | CAP,10nF,+/-10%,X7R,50V,G,SMD0402 | MURATA ELEC. NORTH AMERICA | GRM155R71H103K | 3 | N | PSRC9,PSLC9,PSGC9 |
|  | Y | 2 | Y(3) | 17 | 620105U00-015-G | - | CAP,220pF,+/-10%,X7R,50V,G,SMD0402 | MURATA ELEC. NORTH AMERICA | GRM155R71H221K | 3 | N | PSRC13,PSLC13,PSGC13 |
|  | N | ND | Y(4) | 18 | 610112M00-017-G |  | RES,13KOhm,+/-1%,1/16W,G,SMD0402 | KOA SPEER ELECTRONICS, INC. | RK73H1ETTP1302F | 2 | N | PSLR1,PSGR1 |
|  | N | ND | Y(4) | 19 | 610114H00-017-G | - | RES,20KOhm,+/-1%,1/16W,G,SMD0402 | KOA SPEER ELECTRONICS, INC. | RK73H1ETTP2002F | 2 | N | PSLR3,PSGR3 |
|  | ND | ND | Y(4) | 20 | 61011HA00-017-G |  | RES,1 Ohm,+/-1%,1/16W,G,SMD0402 | KOA SPEER ELECTRONICS, INC. | RK73H1ETTP1R00F | 3 | N | PSRR14,PSLR14,PSGR14 |
|  | ND |  | Y(4) | 21 | 61012JH00-017-G |  | RES,470 Ohm,+/-5%,1/8W,G,SMD0805 | KOA SPEER ELECTRONICS, INC. | RK73B2ATTD471J | 2 | N | PSRR20,PSLR20 |
|  | N | Other | Y(4) | 22 | 61010JY00-017-G | - | RES,220 Ohm,+/-5%,1/16W,G,SMD0402 | KOA SPEER ELECTRONICS, INC. | RK73B1ETTP221J | 6 | N | R7,R140,R142,R191,R193,R199 |
|  | N | ND | Y(4) | 23 | 610114J00-017-G | - | RES,2KOhm,+/-1%,1/16W,G,SMD0402 | KOA SPEER ELECTRONICS, INC. | RK73H1ETTP2001F | 7 | N | R19,R20,R21,R22,R23,R24,R25 |
|  |  |  | Y(4) | 24 | 610112W00-017-G |  | RES,2KOhm,+/-5%,1/16W,G,SMD0402 | KOA SPEER ELECTRONICS, INC. | RK73B1ETTP202J | 12 | N | R31,R32,R35,R37,R52,R56,R85,R88,R94,R100,R101,R138 |
|  | N | Other | Y(4) | 25 | 61011MQ00-017-G | - | RES,4.75KOhm,+/-1%,1/16W,G,SMD0402 | KOA SPEER ELECTRONICS, INC. | RK73H1ETTP4751F | 10 | N | R33,R86,R186,R187,R196,R197,R249,R1478,R1479,R1480 |
|  | ND | ND | Y(4) | 26 | 61010L100-017-G | - | RES,100KOhm,+/-1%,1/16W,G,SMD0402 | KOA SPEER ELECTRONICS, INC. | RK73H1ETTP1003F | 4 | N | R236,R239,R244,R246 |
|  | N | ND | Y(4) | 27 | 61010L300-017-G | - | RES,1KOhm,+/-1%,1/16W,G,SMD0402 | KOA SPEER ELECTRONICS, INC. | RK73H1ETTP1001F | 45 | N | R264,R265,R266,R267,R277,R278,R279,R280,R290,R291,R292,R293,R306,R307,R308,R309,R319,R320,R321,R322,R335,R336,R337,R338,R381,R391,R392,R399,R400,R401,R402,R409,R410,R411,R412,R413,R414,R421,R422,R423,R424,R425,R426,R436,R437 |
|  | ND | ND | Y(4) | 28 | 61011WQ00-017-G | - | RES,3KOhm,+/-1%,1/16W,G,SMD0402 | KOA SPEER ELECTRONICS, INC. | RK73H1ETTP3001F | 2 | N | R385,R386 |
|  | N | Other | Y(4) | 29 | 61011B300-017-G | - | RES,1MOhm,+/-1%,1/16W,G,SMD0402 | KOA SPEER ELECTRONICS, INC. | RK73H1ETTP1004F | 1 | N | R710 |
|  | N | other | Y(4) | 30 | 610107C00-017-G | K9577 | RES,10KOhm,+/-5%,1/16W,G,SMD0402 | KOA SPEER ELECTRONICS, INC. | RK73B1ETTP103J | 1 | N | R1412 |
|  | N | other | Y(4) | 31 | 610100T00-017-G |  | RES,1KOhm,+/-5%,1/16W,G,SMD0402 | KOA SPEER ELECTRONICS, INC. | RK73B1ETTP102J | 1 | N | R1509 |
|  | N | ND | Y(4) | 32 | 610118100-017-G | - | RES,1.4KOhm,+/-1%,1/16W,G,SMD0402 | KOA SPEER ELECTRONICS, INC. | RK73H1ETTP1401F | 2 | N | R1533,R1534 |
|  | N | 1 | Y(1) | 33 | 420103G00-244-G | - | SRAM,CY14V101LA-BA45XIT,3.0~3.6V,1M,G,FBGA-48,SMD | CYPRESS SEMICONDUCTOR CORP | CY14V101LA-BA45XIT | 1 | N | U_EXP_NVSRAM2 |
|  | N | ND | Y(3) | 34 | 310101400-031-G | - | IC,Gate&Inverter,74LVC1G08GW,1.65~5.5V,G,SOT353-5,SMD | NXP SEMICONDUCTORS | 74LVC1G08GW | 1 | N | U5 |
|  | Y | 1 | N | 35 | 34062K700-742-G |  | CONN,Socket,2X28,V/T,0.5mm,G,SMD-56 | MERITEC | 980020-56-P1-K | 1 | Y | J_FLASH_SOCKET1 |
